(kicad_pcb
	(version 20260206)
	(generator "pcbnew")
	(generator_version "10.0")
	(general
		(thickness 1.6)
		(legacy_teardrops no)
	)
	(paper "A4")
	(title_block
		(title "netronome-mezz — pcbd0082-001_rev01_jul9_a.brd")
		(comment 1 "Open CloudServer (Microsoft) / footprints 280-288 of 714")
	)
	(layers
		(0 "F.Cu" signal "TOP")
		(4 "In1.Cu" signal "02_GND")
		(6 "In2.Cu" signal "03_SIG")
		(8 "In3.Cu" signal "04_SIG")
		(10 "In4.Cu" signal "05_GND")
		(12 "In5.Cu" signal "06_PWR1")
		(14 "In6.Cu" signal "07_SIG")
		(16 "In7.Cu" signal "08_SIG")
		(18 "In8.Cu" signal "09_GND")
		(2 "B.Cu" signal "BOTTOM")
		(9 "F.Adhes" user "F.Adhesive")
		(11 "B.Adhes" user "B.Adhesive")
		(13 "F.Paste" user "Package Geometry/Pastemask Top")
		(15 "B.Paste" user "Package Geometry/Pastemask Bottom")
		(5 "F.SilkS" user "Ref Des/Silkscreen Top")
		(7 "B.SilkS" user "Ref Des/Silkscreen Bottom")
		(1 "F.Mask" user "Board Geometry/Soldermask Top")
		(3 "B.Mask" user "Board Geometry/Soldermask Bottom")
		(17 "Dwgs.User" user "User.Drawings")
		(19 "Cmts.User" user "User.Comments")
		(21 "Eco1.User" user "User.Eco1")
		(23 "Eco2.User" user "User.Eco2")
		(25 "Edge.Cuts" user "Board Geometry/Outline")
		(27 "Margin" user)
		(31 "F.CrtYd" user "Package Geometry/Place Bound Top")
		(29 "B.CrtYd" user "Package Geometry/Place Bound Bottom")
		(35 "F.Fab" user "Ref Des/Assembly Top")
		(33 "B.Fab" user "Ref Des/Assembly Bottom")
		(45 "User.4" user "COMPVAL_TYPE_BOTTOM")
	)
	(footprint ""
		(layer "F.Cu")
		(at 21.971 35.687 180)
		(property "Reference" "R70"
			(at 0 0 180)
			(layer "F.SilkS")
			(hide yes)
			(effects
				(font
					(size 1.27 1.27)
				)
			)
		)
		(property "Value" "4.75K"
			(at -0.148158 1.3462 270)
			(unlocked yes)
			(layer "F.Fab")
			(hide yes)
			(effects
				(font
					(size 1.27 0.9652)
					(thickness 0.000001)
				)
				(justify left)
			)
		)
		(property "Device Type" "REST4024"
			(at -0.148158 1.3462 270)
			(unlocked yes)
			(layer "F.Fab")
			(hide yes)
			(effects
				(font
					(size 1.27 0.9652)
					(thickness 0.000001)
				)
				(justify left)
			)
		)
		(duplicate_pad_numbers_are_jumpers no)
		(fp_poly
			(pts
				(xy 0.635 1.0668) (xy 0.635 -1.0668) (xy -0.635 -1.0668) (xy -0.635 1.0668)
			)
			(stroke
				(width 0)
				(type default)
			)
			(fill no)
			(layer "F.CrtYd")
		)
		(fp_line
			(start 0.254 0.508)
			(end -0.254 0.508)
			(stroke
				(width 0.0254)
				(type default)
			)
			(layer "F.Fab")
		)
		(fp_line
			(start 0.254 -0.508)
			(end 0.254 0.508)
			(stroke
				(width 0.0254)
				(type default)
			)
			(layer "F.Fab")
		)
		(fp_line
			(start -0.254 0.508)
			(end -0.254 -0.508)
			(stroke
				(width 0.0254)
				(type default)
			)
			(layer "F.Fab")
		)
		(fp_line
			(start -0.254 -0.508)
			(end 0.254 -0.508)
			(stroke
				(width 0.0254)
				(type default)
			)
			(layer "F.Fab")
		)
		(pad "1" smd rect
			(at 0 -0.4191 180)
			(size 0.508 0.5334)
			(layers "F.Cu" "F.Mask" "F.Paste")
			(net "EXT_3.3V")
		)
		(pad "2" smd rect
			(at 0 0.4191 180)
			(size 0.508 0.5334)
			(layers "F.Cu" "F.Mask" "F.Paste")
			(net "DEBUG_CPLD_PGRM_JTAG_TDO")
		)
		(zone
			(layer "F.Cu")
			(hatch none 0.5)
			(connect_pads
				(clearance 0)
			)
			(min_thickness 0.25)
			(keepout
				(tracks not_allowed)
				(vias allowed)
				(pads allowed)
				(copperpour not_allowed)
				(footprints allowed)
			)
			(placement
				(enabled no)
				(sheetname "")
			)
			(fill
				(thermal_gap 0.5)
				(thermal_bridge_width 0.5)
				(island_removal_mode 0)
			)
			(polygon
				(pts
					(xy 21.9456 35.7124) (xy 21.9456 35.6616) (xy 21.9964 35.6616) (xy 21.9964 35.7124)
				)
			)
		)
	)
	(footprint ""
		(layer "F.Cu")
		(at 28.702 44.323)
		(property "Reference" "C48"
			(at 0 0 0)
			(layer "F.SilkS")
			(hide yes)
			(effects
				(font
					(size 1.27 1.27)
				)
			)
		)
		(property "Value" "1000PF"
			(at -0.091846 0.2921 90)
			(unlocked yes)
			(layer "F.Fab")
			(hide yes)
			(effects
				(font
					(size 0.7874 0.5842)
					(thickness 0.2032)
				)
				(justify left)
			)
		)
		(property "Device Type" "CAPC0083"
			(at -0.091846 0.2921 90)
			(unlocked yes)
			(layer "F.Fab")
			(hide yes)
			(effects
				(font
					(size 0.7874 0.5842)
					(thickness 0.2032)
				)
				(justify left)
			)
		)
		(duplicate_pad_numbers_are_jumpers no)
		(fp_poly
			(pts
				(xy 0.635 1.0668) (xy 0.635 -1.0668) (xy -0.635 -1.0668) (xy -0.635 1.0668)
			)
			(stroke
				(width 0)
				(type default)
			)
			(fill no)
			(layer "F.CrtYd")
		)
		(fp_line
			(start -0.254 -0.508)
			(end 0.254 -0.508)
			(stroke
				(width 0.0254)
				(type default)
			)
			(layer "F.Fab")
		)
		(fp_line
			(start -0.254 0.508)
			(end -0.254 -0.508)
			(stroke
				(width 0.0254)
				(type default)
			)
			(layer "F.Fab")
		)
		(fp_line
			(start 0.254 -0.508)
			(end 0.254 0.508)
			(stroke
				(width 0.0254)
				(type default)
			)
			(layer "F.Fab")
		)
		(fp_line
			(start 0.254 0.508)
			(end -0.254 0.508)
			(stroke
				(width 0.0254)
				(type default)
			)
			(layer "F.Fab")
		)
		(pad "1" smd rect
			(at 0 -0.4191)
			(size 0.508 0.5334)
			(layers "F.Cu" "F.Mask" "F.Paste")
			(net "10N2384")
		)
		(pad "2" smd rect
			(at 0 0.4191)
			(size 0.508 0.5334)
			(layers "F.Cu" "F.Mask" "F.Paste")
			(net "10N2386")
		)
		(zone
			(layer "F.Cu")
			(hatch none 0.5)
			(connect_pads
				(clearance 0)
			)
			(min_thickness 0.25)
			(keepout
				(tracks not_allowed)
				(vias allowed)
				(pads allowed)
				(copperpour not_allowed)
				(footprints allowed)
			)
			(placement
				(enabled no)
				(sheetname "")
			)
			(fill
				(thermal_gap 0.5)
				(thermal_bridge_width 0.5)
				(island_removal_mode 0)
			)
			(polygon
				(pts
					(xy 28.7274 44.2976) (xy 28.7274 44.3484) (xy 28.6766 44.3484) (xy 28.6766 44.2976)
				)
			)
		)
	)
	(footprint ""
		(layer "F.Cu")
		(at 2.159 36.83)
		(property "Reference" "TP15"
			(at -2.921 -1.49733 0)
			(unlocked yes)
			(layer "F.SilkS")
			(effects
				(font
					(size 0.7874 0.5842)
					(thickness 0.127)
				)
				(justify left)
			)
		)
		(property "Value" "*"
			(at -0.4826 -0.14732 0)
			(unlocked yes)
			(layer "F.Fab")
			(hide yes)
			(effects
				(font
					(size 1.27 0.9652)
					(thickness 0.000001)
				)
				(justify left)
			)
		)
		(property "Device Type" "TP_SMALL"
			(at -0.4826 -0.14732 0)
			(unlocked yes)
			(layer "F.Fab")
			(hide yes)
			(effects
				(font
					(size 1.27 0.9652)
					(thickness 0.000001)
				)
				(justify left)
			)
		)
		(duplicate_pad_numbers_are_jumpers no)
		(fp_line
			(start -0.8636 -0.8636)
			(end -0.8636 0.8636)
			(stroke
				(width 0.1524)
				(type default)
			)
			(layer "F.SilkS")
		)
		(fp_line
			(start -0.8636 0.8636)
			(end 0.8636 0.8636)
			(stroke
				(width 0.1524)
				(type default)
			)
			(layer "F.SilkS")
		)
		(fp_line
			(start 0.8636 -0.8636)
			(end -0.8636 -0.8636)
			(stroke
				(width 0.1524)
				(type default)
			)
			(layer "F.SilkS")
		)
		(fp_line
			(start 0.8636 0.8636)
			(end 0.8636 -0.8636)
			(stroke
				(width 0.1524)
				(type default)
			)
			(layer "F.SilkS")
		)
		(fp_poly
			(pts
				(xy -0.635 -0.635) (xy -0.635 0.635) (xy 0.635 0.635) (xy 0.635 -0.635)
			)
			(stroke
				(width 0)
				(type default)
			)
			(fill no)
			(layer "F.CrtYd")
		)
		(pad "1" smd rect
			(at 0 0)
			(size 1.27 1.27)
			(layers "F.Cu" "F.Mask" "F.Paste")
			(net "PSU_I2C_SCL")
		)
	)
	(footprint ""
		(layer "F.Cu")
		(at 29.972 42.926 90)
		(property "Reference" "C52"
			(at 0 0 90)
			(layer "F.SilkS")
			(hide yes)
			(effects
				(font
					(size 1.27 1.27)
				)
			)
		)
		(property "Value" "68PF"
			(at -0.091846 0.2921 180)
			(unlocked yes)
			(layer "F.Fab")
			(hide yes)
			(effects
				(font
					(size 0.7874 0.5842)
					(thickness 0.2032)
				)
				(justify left)
			)
		)
		(property "Device Type" "CAPC0030"
			(at -0.091846 0.2921 180)
			(unlocked yes)
			(layer "F.Fab")
			(hide yes)
			(effects
				(font
					(size 0.7874 0.5842)
					(thickness 0.2032)
				)
				(justify left)
			)
		)
		(duplicate_pad_numbers_are_jumpers no)
		(fp_poly
			(pts
				(xy 0.635 1.0668) (xy 0.635 -1.0668) (xy -0.635 -1.0668) (xy -0.635 1.0668)
			)
			(stroke
				(width 0)
				(type default)
			)
			(fill no)
			(layer "F.CrtYd")
		)
		(fp_line
			(start 0.254 -0.508)
			(end 0.254 0.508)
			(stroke
				(width 0.0254)
				(type default)
			)
			(layer "F.Fab")
		)
		(fp_line
			(start -0.254 -0.508)
			(end 0.254 -0.508)
			(stroke
				(width 0.0254)
				(type default)
			)
			(layer "F.Fab")
		)
		(fp_line
			(start 0.254 0.508)
			(end -0.254 0.508)
			(stroke
				(width 0.0254)
				(type default)
			)
			(layer "F.Fab")
		)
		(fp_line
			(start -0.254 0.508)
			(end -0.254 -0.508)
			(stroke
				(width 0.0254)
				(type default)
			)
			(layer "F.Fab")
		)
		(pad "1" smd rect
			(at 0 -0.4191 90)
			(size 0.508 0.5334)
			(layers "F.Cu" "F.Mask" "F.Paste")
			(net "10N2384")
		)
		(pad "2" smd rect
			(at 0 0.4191 90)
			(size 0.508 0.5334)
			(layers "F.Cu" "F.Mask" "F.Paste")
			(net "10N2504")
		)
		(zone
			(layer "F.Cu")
			(hatch none 0.5)
			(connect_pads
				(clearance 0)
			)
			(min_thickness 0.25)
			(keepout
				(tracks not_allowed)
				(vias allowed)
				(pads allowed)
				(copperpour not_allowed)
				(footprints allowed)
			)
			(placement
				(enabled no)
				(sheetname "")
			)
			(fill
				(thermal_gap 0.5)
				(thermal_bridge_width 0.5)
				(island_removal_mode 0)
			)
			(polygon
				(pts
					(xy 29.9466 42.9006) (xy 29.9974 42.9006) (xy 29.9974 42.9514) (xy 29.9466 42.9514)
				)
			)
		)
	)
	(footprint ""
		(layer "F.Cu")
		(at 76.251003 15.056002)
		(property "Reference" "V_A-DQS2-P"
			(at 0 0 0)
			(layer "F.SilkS")
			(hide yes)
			(effects
				(font
					(size 1.27 1.27)
				)
			)
		)
		(property "Value" ""
			(at 0 0 0)
			(layer "F.Fab")
			(effects
				(font
					(size 1.27 1.27)
				)
			)
		)
		(duplicate_pad_numbers_are_jumpers no)
		(pad "1" thru_hole circle
			(at 0 0)
			(size 0.762 0.762)
			(drill 0.20574)
			(layers "*.Cu" "*.Mask")
			(remove_unused_layers no)
			(net "DDR0_32A_DQS2_P")
			(clearance 0.127)
			(thermal_gap 0.127)
			(padstack
				(mode front_inner_back)
				(layer "Inner"
					(shape circle)
					(size 0.4572 0.4572)
					(clearance 0.1143)
				)
				(layer "B.Cu"
					(shape circle)
					(size 0.4572 0.4572)
					(clearance 0.1143)
				)
			)
		)
	)
	(footprint ""
		(layer "F.Cu")
		(at 35.941 5.207 90)
		(property "Reference" "C83"
			(at 0 0 90)
			(layer "F.SilkS")
			(hide yes)
			(effects
				(font
					(size 1.27 1.27)
				)
			)
		)
		(property "Value" "0.1UF"
			(at -0.091846 0.2921 180)
			(unlocked yes)
			(layer "F.Fab")
			(hide yes)
			(effects
				(font
					(size 0.7874 0.5842)
					(thickness 0.2032)
				)
				(justify left)
			)
		)
		(property "Device Type" "CAPC0073"
			(at -0.091846 0.2921 180)
			(unlocked yes)
			(layer "F.Fab")
			(hide yes)
			(effects
				(font
					(size 0.7874 0.5842)
					(thickness 0.2032)
				)
				(justify left)
			)
		)
		(duplicate_pad_numbers_are_jumpers no)
		(fp_poly
			(pts
				(xy 0.635 1.0668) (xy 0.635 -1.0668) (xy -0.635 -1.0668) (xy -0.635 1.0668)
			)
			(stroke
				(width 0)
				(type default)
			)
			(fill no)
			(layer "F.CrtYd")
		)
		(fp_line
			(start 0.254 -0.508)
			(end 0.254 0.508)
			(stroke
				(width 0.0254)
				(type default)
			)
			(layer "F.Fab")
		)
		(fp_line
			(start -0.254 -0.508)
			(end 0.254 -0.508)
			(stroke
				(width 0.0254)
				(type default)
			)
			(layer "F.Fab")
		)
		(fp_line
			(start 0.254 0.508)
			(end -0.254 0.508)
			(stroke
				(width 0.0254)
				(type default)
			)
			(layer "F.Fab")
		)
		(fp_line
			(start -0.254 0.508)
			(end -0.254 -0.508)
			(stroke
				(width 0.0254)
				(type default)
			)
			(layer "F.Fab")
		)
		(pad "1" smd rect
			(at 0 -0.4191 90)
			(size 0.508 0.5334)
			(layers "F.Cu" "F.Mask" "F.Paste")
			(net "EXT_3.3V")
		)
		(pad "2" smd rect
			(at 0 0.4191 90)
			(size 0.508 0.5334)
			(layers "F.Cu" "F.Mask" "F.Paste")
			(net "GND")
		)
		(zone
			(layer "F.Cu")
			(hatch none 0.5)
			(connect_pads
				(clearance 0)
			)
			(min_thickness 0.25)
			(keepout
				(tracks not_allowed)
				(vias allowed)
				(pads allowed)
				(copperpour not_allowed)
				(footprints allowed)
			)
			(placement
				(enabled no)
				(sheetname "")
			)
			(fill
				(thermal_gap 0.5)
				(thermal_bridge_width 0.5)
				(island_removal_mode 0)
			)
			(polygon
				(pts
					(xy 35.9156 5.1816) (xy 35.9664 5.1816) (xy 35.9664 5.2324) (xy 35.9156 5.2324)
				)
			)
		)
	)
	(footprint ""
		(layer "F.Cu")
		(at 35.941 4.064 90)
		(property "Reference" "C24"
			(at 0.73533 -0.254 0)
			(unlocked yes)
			(layer "F.SilkS")
			(effects
				(font
					(size 0.7874 0.5842)
					(thickness 0.127)
				)
				(justify left)
			)
		)
		(property "Value" "0.01UF"
			(at -0.091846 0.2921 180)
			(unlocked yes)
			(layer "F.Fab")
			(hide yes)
			(effects
				(font
					(size 0.7874 0.5842)
					(thickness 0.2032)
				)
				(justify left)
			)
		)
		(property "Device Type" "CAPC1553"
			(at -0.091846 0.2921 180)
			(unlocked yes)
			(layer "F.Fab")
			(hide yes)
			(effects
				(font
					(size 0.7874 0.5842)
					(thickness 0.2032)
				)
				(justify left)
			)
		)
		(duplicate_pad_numbers_are_jumpers no)
		(fp_poly
			(pts
				(xy 0.635 1.0668) (xy 0.635 -1.0668) (xy -0.635 -1.0668) (xy -0.635 1.0668)
			)
			(stroke
				(width 0)
				(type default)
			)
			(fill no)
			(layer "F.CrtYd")
		)
		(fp_line
			(start 0.254 -0.508)
			(end 0.254 0.508)
			(stroke
				(width 0.0254)
				(type default)
			)
			(layer "F.Fab")
		)
		(fp_line
			(start -0.254 -0.508)
			(end 0.254 -0.508)
			(stroke
				(width 0.0254)
				(type default)
			)
			(layer "F.Fab")
		)
		(fp_line
			(start 0.254 0.508)
			(end -0.254 0.508)
			(stroke
				(width 0.0254)
				(type default)
			)
			(layer "F.Fab")
		)
		(fp_line
			(start -0.254 0.508)
			(end -0.254 -0.508)
			(stroke
				(width 0.0254)
				(type default)
			)
			(layer "F.Fab")
		)
		(pad "1" smd rect
			(at 0 -0.4191 90)
			(size 0.508 0.5334)
			(layers "F.Cu" "F.Mask" "F.Paste")
			(net "EXT_3.3V")
		)
		(pad "2" smd rect
			(at 0 0.4191 90)
			(size 0.508 0.5334)
			(layers "F.Cu" "F.Mask" "F.Paste")
			(net "GND")
		)
		(zone
			(layer "F.Cu")
			(hatch none 0.5)
			(connect_pads
				(clearance 0)
			)
			(min_thickness 0.25)
			(keepout
				(tracks not_allowed)
				(vias allowed)
				(pads allowed)
				(copperpour not_allowed)
				(footprints allowed)
			)
			(placement
				(enabled no)
				(sheetname "")
			)
			(fill
				(thermal_gap 0.5)
				(thermal_bridge_width 0.5)
				(island_removal_mode 0)
			)
			(polygon
				(pts
					(xy 35.9156 4.0386) (xy 35.9664 4.0386) (xy 35.9664 4.0894) (xy 35.9156 4.0894)
				)
			)
		)
	)
	(footprint ""
		(layer "F.Cu")
		(at 17.399 6.985)
		(property "Reference" "R392"
			(at 0.15367 3.81 90)
			(unlocked yes)
			(layer "F.SilkS")
			(effects
				(font
					(size 0.7874 0.5842)
					(thickness 0.127)
				)
				(justify left)
			)
		)
		(property "Value" "0"
			(at -0.148158 1.3462 90)
			(unlocked yes)
			(layer "F.Fab")
			(hide yes)
			(effects
				(font
					(size 1.27 0.9652)
					(thickness 0.000001)
				)
				(justify left)
			)
		)
		(property "Device Type" "REST1111"
			(at -0.148158 1.3462 90)
			(unlocked yes)
			(layer "F.Fab")
			(hide yes)
			(effects
				(font
					(size 1.27 0.9652)
					(thickness 0.000001)
				)
				(justify left)
			)
		)
		(duplicate_pad_numbers_are_jumpers no)
		(fp_poly
			(pts
				(xy 0.635 1.0668) (xy 0.635 -1.0668) (xy -0.635 -1.0668) (xy -0.635 1.0668)
			)
			(stroke
				(width 0)
				(type default)
			)
			(fill no)
			(layer "F.CrtYd")
		)
		(fp_line
			(start -0.254 -0.508)
			(end 0.254 -0.508)
			(stroke
				(width 0.0254)
				(type default)
			)
			(layer "F.Fab")
		)
		(fp_line
			(start -0.254 0.508)
			(end -0.254 -0.508)
			(stroke
				(width 0.0254)
				(type default)
			)
			(layer "F.Fab")
		)
		(fp_line
			(start 0.254 -0.508)
			(end 0.254 0.508)
			(stroke
				(width 0.0254)
				(type default)
			)
			(layer "F.Fab")
		)
		(fp_line
			(start 0.254 0.508)
			(end -0.254 0.508)
			(stroke
				(width 0.0254)
				(type default)
			)
			(layer "F.Fab")
		)
		(pad "1" smd rect
			(at 0 -0.4191)
			(size 0.508 0.5334)
			(layers "F.Cu" "F.Mask" "F.Paste")
			(net "CPLD_SMBUS_ALERT_L")
		)
		(pad "2" smd rect
			(at 0 0.4191)
			(size 0.508 0.5334)
			(layers "F.Cu" "F.Mask" "F.Paste")
			(net "SMBUS_ALERT_L")
		)
		(zone
			(layer "F.Cu")
			(hatch none 0.5)
			(connect_pads
				(clearance 0)
			)
			(min_thickness 0.25)
			(keepout
				(tracks not_allowed)
				(vias allowed)
				(pads allowed)
				(copperpour not_allowed)
				(footprints allowed)
			)
			(placement
				(enabled no)
				(sheetname "")
			)
			(fill
				(thermal_gap 0.5)
				(thermal_bridge_width 0.5)
				(island_removal_mode 0)
			)
			(polygon
				(pts
					(xy 17.4244 6.9596) (xy 17.4244 7.0104) (xy 17.3736 7.0104) (xy 17.3736 6.9596)
				)
			)
		)
	)
	(footprint ""
		(layer "F.Cu")
		(at 14.605 44.196 180)
		(property "Reference" "L19"
			(at -2.43967 -1.27 90)
			(unlocked yes)
			(layer "F.SilkS")
			(effects
				(font
					(size 0.7874 0.5842)
					(thickness 0.127)
				)
				(justify left)
			)
		)
		(property "Value" "1.0UH"
			(at -0.483362 -0.148082 180)
			(unlocked yes)
			(layer "F.Fab")
			(hide yes)
			(effects
				(font
					(size 1.27 0.9652)
					(thickness 0.000001)
				)
				(justify left)
			)
		)
		(property "Device Type" "INDS0061"
			(at -0.483362 -0.148082 180)
			(unlocked yes)
			(layer "F.Fab")
			(hide yes)
			(effects
				(font
					(size 1.27 0.9652)
					(thickness 0.000001)
				)
				(justify left)
			)
		)
		(duplicate_pad_numbers_are_jumpers no)
		(fp_line
			(start 1.27 1.397)
			(end -1.27 1.397)
			(stroke
				(width 0.1524)
				(type default)
			)
			(layer "F.SilkS")
		)
		(fp_line
			(start -1.27 -1.397)
			(end 1.27 -1.397)
			(stroke
				(width 0.1524)
				(type default)
			)
			(layer "F.SilkS")
		)
		(fp_poly
			(pts
				(xy 2.159 -1.651) (xy 2.159 1.651) (xy -2.159 1.651) (xy -2.159 -1.651)
			)
			(stroke
				(width 0)
				(type default)
			)
			(fill no)
			(layer "F.CrtYd")
		)
		(fp_line
			(start 1.3462 1.1049)
			(end 1.3462 -1.1049)
			(stroke
				(width 0.1524)
				(type default)
			)
			(layer "F.Fab")
		)
		(fp_line
			(start 1.3462 -1.1049)
			(end -1.3462 -1.1049)
			(stroke
				(width 0.1524)
				(type default)
			)
			(layer "F.Fab")
		)
		(fp_line
			(start -1.3462 1.1049)
			(end 1.3462 1.1049)
			(stroke
				(width 0.1524)
				(type default)
			)
			(layer "F.Fab")
		)
		(fp_line
			(start -1.3462 -1.1049)
			(end -1.3462 1.1049)
			(stroke
				(width 0.1524)
				(type default)
			)
			(layer "F.Fab")
		)
		(pad "1" smd rect
			(at -1.1303 0 180)
			(size 1.1938 2.3368)
			(layers "F.Cu" "F.Mask" "F.Paste")
			(net "VDD_1.8V")
		)
		(pad "2" smd rect
			(at 1.1303 0 180)
			(size 1.1938 2.3368)
			(layers "F.Cu" "F.Mask" "F.Paste")
			(net "11N1937")
		)
		(zone
			(layer "F.Cu")
			(hatch none 0.5)
			(connect_pads
				(clearance 0)
			)
			(min_thickness 0.25)
			(keepout
				(tracks allowed)
				(vias not_allowed)
				(pads allowed)
				(copperpour not_allowed)
				(footprints allowed)
			)
			(placement
				(enabled no)
				(sheetname "")
			)
			(fill
				(thermal_gap 0.5)
				(thermal_bridge_width 0.5)
				(island_removal_mode 0)
			)
			(polygon
				(pts
					(xy 15.9512 43.0911) (xy 13.2588 43.0911) (xy 13.2588 45.3009) (xy 15.9512 45.3009)
				)
			)
		)
	)
)
